(kicad_pcb
	(version 20260206)
	(generator "pcbnew")
	(generator_version "10.0")
	(general
		(thickness 1.6)
		(legacy_teardrops no)
	)
	(paper "A4")
	(title_block
		(title "v1-chassis-manager — T6M_CM_d_v01_1031_1645.brd")
		(comment 1 "Open CloudServer (Microsoft) / footprint 1507 of 2512 (U2), pads 949-1066 of 1283")
	)
	(layers
		(0 "F.Cu" signal "TOP")
		(4 "In1.Cu" signal "GND1")
		(6 "In2.Cu" signal "IN1")
		(8 "In3.Cu" signal "VCC1")
		(10 "In4.Cu" signal "VCC2")
		(12 "In5.Cu" signal "GND2")
		(14 "In6.Cu" signal "IN2")
		(16 "In7.Cu" signal "IN3")
		(18 "In8.Cu" signal "GND3")
		(2 "B.Cu" signal "BOTTOM")
		(9 "F.Adhes" user "F.Adhesive")
		(11 "B.Adhes" user "B.Adhesive")
		(13 "F.Paste" user "Package Geometry/Pastemask Top")
		(15 "B.Paste" user "Package Geometry/Pastemask Bottom")
		(5 "F.SilkS" user "Ref Des/Silkscreen Top")
		(7 "B.SilkS" user "Ref Des/Silkscreen Bottom")
		(1 "F.Mask" user "Board Geometry/Soldermask Top")
		(3 "B.Mask" user "Board Geometry/Soldermask Bottom")
		(17 "Dwgs.User" user "User.Drawings")
		(19 "Cmts.User" user "User.Comments")
		(21 "Eco1.User" user "User.Eco1")
		(23 "Eco2.User" user "User.Eco2")
		(25 "Edge.Cuts" user "Board Geometry/Outline")
		(27 "Margin" user)
		(31 "F.CrtYd" user "Package Geometry/Place Bound Top")
		(29 "B.CrtYd" user "Package Geometry/Place Bound Bottom")
		(35 "F.Fab" user "Ref Des/Assembly Top")
		(33 "B.Fab" user "Ref Des/Assembly Bottom")
	)
	(footprint ""
		(layer "F.Cu")
		(at 58.000646 -75.799442)
		(property "Reference" "U2"
			(at -20.2438 -18.364708 0)
			(unlocked yes)
			(layer "F.SilkS")
			(effects
				(font
					(size 1.6002 1.1938)
					(thickness 0.1524)
				)
				(justify left)
			)
		)
		(property "Value" ""
			(at 0 0 0)
			(layer "F.Fab")
			(effects
				(font
					(size 1.27 1.27)
				)
			)
		)
		(duplicate_pad_numbers_are_jumpers no)
		(pad "E62" smd circle
			(at 14.485366 -11.485372)
			(size 0.4064 0.4064)
			(layers "F.Cu" "F.Mask" "F.Paste")
			(net "GND")
		)
		(pad "E64" smd circle
			(at 15.298166 -11.485372)
			(size 0.4064 0.4064)
			(layers "F.Cu" "F.Mask" "F.Paste")
			(net "GND")
		)
		(pad "E66" smd circle
			(at 16.110966 -11.485372)
			(size 0.4064 0.4064)
			(layers "F.Cu" "F.Mask" "F.Paste")
			(net "GND")
		)
		(pad "F1" smd circle
			(at -16.110966 -10.672572)
			(size 0.4064 0.4064)
			(layers "F.Cu" "F.Mask" "F.Paste")
			(net "TP_CPU_NODE1_HPLL_MONP")
		)
		(pad "F4" smd circle
			(at -14.90091 -10.696448)
			(size 0.3048 0.3048)
			(layers "F.Cu" "F.Mask" "F.Paste")
			(net "GND")
		)
		(pad "F5" smd circle
			(at -14.204442 -10.813796)
			(size 0.3048 0.3048)
			(layers "F.Cu" "F.Mask" "F.Paste")
			(net "PD_NODE1_NTB_PERN")
		)
		(pad "F63" smd circle
			(at 14.90091 -10.903712)
			(size 0.3048 0.3048)
			(layers "F.Cu" "F.Mask" "F.Paste")
			(net "GND")
		)
		(pad "F66" smd circle
			(at 16.110966 -10.672572)
			(size 0.4064 0.4064)
			(layers "F.Cu" "F.Mask" "F.Paste")
			(net "GND")
		)
		(pad "G3" smd circle
			(at -15.297912 -10.11047)
			(size 0.3048 0.3048)
			(layers "F.Cu" "F.Mask" "F.Paste")
			(net "GND")
		)
		(pad "G5" smd circle
			(at -14.08049 -10.120376)
			(size 0.3048 0.3048)
			(layers "F.Cu" "F.Mask" "F.Paste")
			(net "PD_NODE1_NTB_PERP")
		)
		(pad "G7" smd circle
			(at -13.344398 -10.161524)
			(size 0.3048 0.3048)
			(layers "F.Cu" "F.Mask" "F.Paste")
			(net "GND")
		)
		(pad "G9" smd circle
			(at -12.38758 -10.344404)
			(size 0.3048 0.3048)
			(layers "F.Cu" "F.Mask" "F.Paste")
			(net "PD_NODE1_NTB_PERN")
		)
		(pad "G10" smd circle
			(at -11.687556 -10.344404)
			(size 0.3048 0.3048)
			(layers "F.Cu" "F.Mask" "F.Paste")
			(net "GND")
		)
		(pad "G17" smd circle
			(at -8.41502 -10.344404)
			(size 0.3048 0.3048)
			(layers "F.Cu" "F.Mask" "F.Paste")
			(net "Net_419")
		)
		(pad "G18" smd circle
			(at -7.714996 -10.344404)
			(size 0.3048 0.3048)
			(layers "F.Cu" "F.Mask" "F.Paste")
			(net "Net_423")
		)
		(pad "G25" smd circle
			(at -4.44246 -10.344404)
			(size 0.3048 0.3048)
			(layers "F.Cu" "F.Mask" "F.Paste")
			(net "Net_403")
		)
		(pad "G26" smd circle
			(at -3.742436 -10.344404)
			(size 0.3048 0.3048)
			(layers "F.Cu" "F.Mask" "F.Paste")
			(net "Net_406")
		)
		(pad "G32" smd circle
			(at -0.4699 -10.344404)
			(size 0.3048 0.3048)
			(layers "F.Cu" "F.Mask" "F.Paste")
			(net "PD_CPU_NODE1_DFX_GPIO_GRP1_7")
		)
		(pad "G34" smd circle
			(at 0.230124 -10.344404)
			(size 0.3048 0.3048)
			(layers "F.Cu" "F.Mask" "F.Paste")
			(net "PD_CPU_NODE1_DFX_GPIO_GRP1_2")
		)
		(pad "G41" smd circle
			(at 3.50266 -10.344404)
			(size 0.3048 0.3048)
			(layers "F.Cu" "F.Mask" "F.Paste")
			(net "LPC_CPU_NODE1_LAD1_R")
		)
		(pad "G42" smd circle
			(at 4.202684 -10.344404)
			(size 0.3048 0.3048)
			(layers "F.Cu" "F.Mask" "F.Paste")
			(net "LPC_CPU_NODE1_LAD0_R")
		)
		(pad "G48" smd circle
			(at 7.47522 -10.344404)
			(size 0.3048 0.3048)
			(layers "F.Cu" "F.Mask" "F.Paste")
			(net "GND")
		)
		(pad "G50" smd circle
			(at 8.175244 -10.344404)
			(size 0.3048 0.3048)
			(layers "F.Cu" "F.Mask" "F.Paste")
			(net "GND")
		)
		(pad "G56" smd circle
			(at 11.44778 -10.344404)
			(size 0.3048 0.3048)
			(layers "F.Cu" "F.Mask" "F.Paste")
			(net "GND")
		)
		(pad "G59" smd circle
			(at 12.582398 -10.344404)
			(size 0.3048 0.3048)
			(layers "F.Cu" "F.Mask" "F.Paste")
			(net "GND")
		)
		(pad "G62" smd circle
			(at 14.013688 -10.32256)
			(size 0.3048 0.3048)
			(layers "F.Cu" "F.Mask" "F.Paste")
			(net "USB_NODE1_SMI_L")
		)
		(pad "G64" smd circle
			(at 15.297912 -10.317734)
			(size 0.3048 0.3048)
			(layers "F.Cu" "F.Mask" "F.Paste")
			(net "H_CPU_NODE1_ERR0")
		)
		(pad "H1" smd oval
			(at -16.110966 -9.859772)
			(size 0.3429 0.2794)
			(layers "F.Cu" "F.Mask" "F.Paste")
			(net "TP_CPU_NODE1_HPLL_MONN")
		)
		(pad "H4" smd circle
			(at -14.751558 -9.581896)
			(size 0.3048 0.3048)
			(layers "F.Cu" "F.Mask" "F.Paste")
			(net "GND")
		)
		(pad "H9" smd circle
			(at -12.38758 -9.582404)
			(size 0.3048 0.3048)
			(layers "F.Cu" "F.Mask" "F.Paste")
			(net "PD_NODE1_NTB_PERP")
		)
		(pad "H10" smd circle
			(at -11.687556 -9.582404)
			(size 0.3048 0.3048)
			(layers "F.Cu" "F.Mask" "F.Paste")
			(net "PD_NODE1_NTB_PERN")
		)
		(pad "H13" smd circle
			(at -10.4013 -9.963404)
			(size 0.3048 0.3048)
			(layers "F.Cu" "F.Mask" "F.Paste")
			(net "Net_421")
		)
		(pad "H14" smd circle
			(at -9.701276 -9.963404)
			(size 0.3048 0.3048)
			(layers "F.Cu" "F.Mask" "F.Paste")
			(net "PD_NODE1_NTB_CLKINN")
		)
		(pad "H17" smd circle
			(at -8.41502 -9.582404)
			(size 0.3048 0.3048)
			(layers "F.Cu" "F.Mask" "F.Paste")
			(net "Net_418")
		)
		(pad "H18" smd circle
			(at -7.714996 -9.582404)
			(size 0.3048 0.3048)
			(layers "F.Cu" "F.Mask" "F.Paste")
			(net "Net_433")
		)
		(pad "H21" smd circle
			(at -6.42874 -9.963404)
			(size 0.3048 0.3048)
			(layers "F.Cu" "F.Mask" "F.Paste")
			(net "GND")
		)
		(pad "H22" smd circle
			(at -5.728716 -9.963404)
			(size 0.3048 0.3048)
			(layers "F.Cu" "F.Mask" "F.Paste")
			(net "GND")
		)
		(pad "H25" smd circle
			(at -4.44246 -9.582404)
			(size 0.3048 0.3048)
			(layers "F.Cu" "F.Mask" "F.Paste")
			(net "Net_429")
		)
		(pad "H26" smd circle
			(at -3.742436 -9.582404)
			(size 0.3048 0.3048)
			(layers "F.Cu" "F.Mask" "F.Paste")
			(net "Net_405")
		)
		(pad "H29" smd circle
			(at -2.45618 -9.963404)
			(size 0.3048 0.3048)
			(layers "F.Cu" "F.Mask" "F.Paste")
			(net "GND")
		)
		(pad "H30" smd circle
			(at -1.756156 -9.963404)
			(size 0.3048 0.3048)
			(layers "F.Cu" "F.Mask" "F.Paste")
			(net "FM_NODE1_DFX_GPIO_GRP05")
		)
		(pad "H32" smd circle
			(at -0.4699 -9.582404)
			(size 0.3048 0.3048)
			(layers "F.Cu" "F.Mask" "F.Paste")
			(net "PD_CPU_NODE1_DFX_GPIO_GRP0_4")
		)
		(pad "H34" smd circle
			(at 0.230124 -9.582404)
			(size 0.3048 0.3048)
			(layers "F.Cu" "F.Mask" "F.Paste")
			(net "PU_CPU_NODE1_DFX_GPIO_GRP1_3")
		)
		(pad "H37" smd circle
			(at 1.51638 -9.963404)
			(size 0.3048 0.3048)
			(layers "F.Cu" "F.Mask" "F.Paste")
			(net "TP_CPU_NODE1_RSVD_MVT1")
		)
		(pad "H38" smd circle
			(at 2.216404 -9.963404)
			(size 0.3048 0.3048)
			(layers "F.Cu" "F.Mask" "F.Paste")
			(net "Net_401")
		)
		(pad "H41" smd circle
			(at 3.50266 -9.582404)
			(size 0.3048 0.3048)
			(layers "F.Cu" "F.Mask" "F.Paste")
			(net "LPC_CPU_NODE1_LAD3_R")
		)
		(pad "H42" smd circle
			(at 4.202684 -9.582404)
			(size 0.3048 0.3048)
			(layers "F.Cu" "F.Mask" "F.Paste")
			(net "LPC_CPU_NODE1_LAD2_R")
		)
		(pad "H44" smd circle
			(at 5.48894 -9.963404)
			(size 0.3048 0.3048)
			(layers "F.Cu" "F.Mask" "F.Paste")
			(net "GND")
		)
		(pad "H46" smd circle
			(at 6.188964 -9.963404)
			(size 0.3048 0.3048)
			(layers "F.Cu" "F.Mask" "F.Paste")
			(net "SPC_CPU_NODE1_DCD_L")
		)
		(pad "H48" smd circle
			(at 7.47522 -9.582404)
			(size 0.3048 0.3048)
			(layers "F.Cu" "F.Mask" "F.Paste")
			(net "H_CPU_NODE1_ERR0_R")
		)
		(pad "H50" smd circle
			(at 8.175244 -9.582404)
			(size 0.3048 0.3048)
			(layers "F.Cu" "F.Mask" "F.Paste")
			(net "SPC_CPU_NODE1_RTS_L")
		)
		(pad "H52" smd circle
			(at 9.4615 -9.963404)
			(size 0.3048 0.3048)
			(layers "F.Cu" "F.Mask" "F.Paste")
			(net "CPU_RSV_1_R")
		)
		(pad "H54" smd circle
			(at 10.161524 -9.963404)
			(size 0.3048 0.3048)
			(layers "F.Cu" "F.Mask" "F.Paste")
			(net "SMB_TEMP1_NODE1_ALERT_L")
		)
		(pad "H56" smd circle
			(at 11.44778 -9.582404)
			(size 0.3048 0.3048)
			(layers "F.Cu" "F.Mask" "F.Paste")
			(net "H_CPU_NODE1_ERR1")
		)
		(pad "H58" smd circle
			(at 12.201398 -9.701276)
			(size 0.3048 0.3048)
			(layers "F.Cu" "F.Mask" "F.Paste")
			(net "GND")
		)
		(pad "H59" smd circle
			(at 12.963398 -9.701276)
			(size 0.3048 0.3048)
			(layers "F.Cu" "F.Mask" "F.Paste")
			(net "NODE1_BIOS_MB_REV_ID2")
		)
		(pad "H62" smd circle
			(at 14.063218 -9.62025)
			(size 0.3048 0.3048)
			(layers "F.Cu" "F.Mask" "F.Paste")
			(net "GND")
		)
		(pad "H63" smd circle
			(at 14.751558 -9.78916)
			(size 0.3048 0.3048)
			(layers "F.Cu" "F.Mask" "F.Paste")
			(net "GND")
		)
		(pad "H66" smd oval
			(at 16.110966 -9.859772)
			(size 0.3429 0.2794)
			(layers "F.Cu" "F.Mask" "F.Paste")
			(net "GND")
		)
		(pad "J5" smd circle
			(at -14.063218 -9.412986)
			(size 0.3048 0.3048)
			(layers "F.Cu" "F.Mask" "F.Paste")
			(net "GND")
		)
		(pad "J13" smd circle
			(at -10.4013 -9.201404)
			(size 0.3048 0.3048)
			(layers "F.Cu" "F.Mask" "F.Paste")
			(net "Net_424")
		)
		(pad "J14" smd circle
			(at -9.701276 -9.201404)
			(size 0.3048 0.3048)
			(layers "F.Cu" "F.Mask" "F.Paste")
			(net "PD_NODE1_NTB_CLKINP")
		)
		(pad "J21" smd circle
			(at -6.42874 -9.201404)
			(size 0.3048 0.3048)
			(layers "F.Cu" "F.Mask" "F.Paste")
			(net "Net_410")
		)
		(pad "J22" smd circle
			(at -5.728716 -9.201404)
			(size 0.3048 0.3048)
			(layers "F.Cu" "F.Mask" "F.Paste")
			(net "Net_415")
		)
		(pad "J29" smd circle
			(at -2.45618 -9.201404)
			(size 0.3048 0.3048)
			(layers "F.Cu" "F.Mask" "F.Paste")
			(net "GND")
		)
		(pad "J30" smd circle
			(at -1.756156 -9.201404)
			(size 0.3048 0.3048)
			(layers "F.Cu" "F.Mask" "F.Paste")
			(net "PD_CPU_NODE1_DFX_GPIO_GRP0_7")
		)
		(pad "J37" smd circle
			(at 1.51638 -9.201404)
			(size 0.3048 0.3048)
			(layers "F.Cu" "F.Mask" "F.Paste")
			(net "H_CPU_NODE1_THRM_LS_L")
		)
		(pad "J38" smd circle
			(at 2.216404 -9.201404)
			(size 0.3048 0.3048)
			(layers "F.Cu" "F.Mask" "F.Paste")
			(net "SPI_CPU_NODE1_SCLK_R")
		)
		(pad "J44" smd circle
			(at 5.48894 -9.201404)
			(size 0.3048 0.3048)
			(layers "F.Cu" "F.Mask" "F.Paste")
			(net "SPC_CPU_NODE1_DSR_L")
		)
		(pad "J46" smd circle
			(at 6.188964 -9.201404)
			(size 0.3048 0.3048)
			(layers "F.Cu" "F.Mask" "F.Paste")
			(net "IRQ_CPU_NODE1_SERIAL_R")
		)
		(pad "J52" smd circle
			(at 9.4615 -9.201404)
			(size 0.3048 0.3048)
			(layers "F.Cu" "F.Mask" "F.Paste")
			(net "GND")
		)
		(pad "J54" smd circle
			(at 10.161524 -9.201404)
			(size 0.3048 0.3048)
			(layers "F.Cu" "F.Mask" "F.Paste")
			(net "GND")
		)
		(pad "J63" smd circle
			(at 14.542516 -9.109456)
			(size 0.3048 0.3048)
			(layers "F.Cu" "F.Mask" "F.Paste")
			(net "FM_CPLD_NODE1_SYS_PG")
		)
		(pad "J64" smd circle
			(at 15.304516 -9.058656)
			(size 0.3048 0.3048)
			(layers "F.Cu" "F.Mask" "F.Paste")
			(net "VR_CPU_NODE1_INTVRMEN")
		)
		(pad "J66" smd oval
			(at 16.249396 -9.109456 90)
			(size 0.254 0.3429)
			(layers "F.Cu" "F.Mask" "F.Paste")
			(net "GND")
		)
		(pad "K1" smd oval
			(at -16.249396 -8.902192 270)
			(size 0.254 0.3429)
			(layers "F.Cu" "F.Mask" "F.Paste")
			(net "GND")
		)
		(pad "K3" smd circle
			(at -15.304516 -8.952992)
			(size 0.3048 0.3048)
			(layers "F.Cu" "F.Mask" "F.Paste")
			(net "PD_NODE1_NTB_PERN")
		)
		(pad "K4" smd circle
			(at -14.542516 -8.902192)
			(size 0.3048 0.3048)
			(layers "F.Cu" "F.Mask" "F.Paste")
			(net "PD_NODE1_NTB_PERP")
		)
		(pad "K10" smd circle
			(at -11.687556 -8.820404)
			(size 0.3048 0.3048)
			(layers "F.Cu" "F.Mask" "F.Paste")
			(net "PD_NODE1_NTB_PERP")
		)
		(pad "K17" smd circle
			(at -8.41502 -8.820404)
			(size 0.3048 0.3048)
			(layers "F.Cu" "F.Mask" "F.Paste")
			(net "GND")
		)
		(pad "K18" smd circle
			(at -7.714996 -8.820404)
			(size 0.3048 0.3048)
			(layers "F.Cu" "F.Mask" "F.Paste")
			(net "GND")
		)
		(pad "K25" smd circle
			(at -4.44246 -8.820404)
			(size 0.3048 0.3048)
			(layers "F.Cu" "F.Mask" "F.Paste")
			(net "GND")
		)
		(pad "K26" smd circle
			(at -3.742436 -8.820404)
			(size 0.3048 0.3048)
			(layers "F.Cu" "F.Mask" "F.Paste")
			(net "GND")
		)
		(pad "K32" smd circle
			(at -0.4699 -8.820404)
			(size 0.3048 0.3048)
			(layers "F.Cu" "F.Mask" "F.Paste")
			(net "GND")
		)
		(pad "K34" smd circle
			(at 0.230124 -8.820404)
			(size 0.3048 0.3048)
			(layers "F.Cu" "F.Mask" "F.Paste")
			(net "GND")
		)
		(pad "K41" smd circle
			(at 3.50266 -8.820404)
			(size 0.3048 0.3048)
			(layers "F.Cu" "F.Mask" "F.Paste")
			(net "GND")
		)
		(pad "K42" smd circle
			(at 4.202684 -8.820404)
			(size 0.3048 0.3048)
			(layers "F.Cu" "F.Mask" "F.Paste")
			(net "GND")
		)
		(pad "K48" smd circle
			(at 7.47522 -8.820404)
			(size 0.3048 0.3048)
			(layers "F.Cu" "F.Mask" "F.Paste")
			(net "CPLD_ROW_LATCH")
		)
		(pad "K50" smd circle
			(at 8.175244 -8.820404)
			(size 0.3048 0.3048)
			(layers "F.Cu" "F.Mask" "F.Paste")
			(net "CPLD_ROW_EN")
		)
		(pad "K62" smd circle
			(at 14.063218 -8.598662)
			(size 0.3048 0.3048)
			(layers "F.Cu" "F.Mask" "F.Paste")
			(net "TP_CPU_NODE1_K62")
		)
		(pad "L2" smd circle
			(at -15.805658 -8.142732)
			(size 0.3048 0.3048)
			(layers "F.Cu" "F.Mask" "F.Paste")
			(net "PD_NODE1_NTB_PERN")
		)
		(pad "L4" smd circle
			(at -14.751558 -8.222488)
			(size 0.3048 0.3048)
			(layers "F.Cu" "F.Mask" "F.Paste")
			(net "PD_NODE1_NTB_PERP")
		)
		(pad "L5" smd circle
			(at -14.063218 -8.391398)
			(size 0.3048 0.3048)
			(layers "F.Cu" "F.Mask" "F.Paste")
			(net "GND")
		)
		(pad "L7" smd circle
			(at -13.344398 -8.175244)
			(size 0.3048 0.3048)
			(layers "F.Cu" "F.Mask" "F.Paste")
			(net "GND")
		)
		(pad "L8" smd circle
			(at -12.582398 -8.175244)
			(size 0.3048 0.3048)
			(layers "F.Cu" "F.Mask" "F.Paste")
			(net "GND")
		)
		(pad "L13" smd circle
			(at -10.4013 -8.439404)
			(size 0.3048 0.3048)
			(layers "F.Cu" "F.Mask" "F.Paste")
			(net "GND")
		)
		(pad "L14" smd circle
			(at -9.701276 -8.439404)
			(size 0.3048 0.3048)
			(layers "F.Cu" "F.Mask" "F.Paste")
			(net "GND")
		)
		(pad "L17" smd circle
			(at -8.41502 -8.058404)
			(size 0.3048 0.3048)
			(layers "F.Cu" "F.Mask" "F.Paste")
			(net "Net_425")
		)
		(pad "L18" smd circle
			(at -7.714996 -8.058404)
			(size 0.3048 0.3048)
			(layers "F.Cu" "F.Mask" "F.Paste")
			(net "Net_420")
		)
		(pad "L21" smd circle
			(at -6.42874 -8.439404)
			(size 0.3048 0.3048)
			(layers "F.Cu" "F.Mask" "F.Paste")
			(net "Net_414")
		)
		(pad "L22" smd circle
			(at -5.728716 -8.439404)
			(size 0.3048 0.3048)
			(layers "F.Cu" "F.Mask" "F.Paste")
			(net "Net_435")
		)
		(pad "L25" smd circle
			(at -4.44246 -8.058404)
			(size 0.3048 0.3048)
			(layers "F.Cu" "F.Mask" "F.Paste")
			(net "Net_432")
		)
		(pad "L26" smd circle
			(at -3.742436 -8.058404)
			(size 0.3048 0.3048)
			(layers "F.Cu" "F.Mask" "F.Paste")
			(net "Net_434")
		)
		(pad "L29" smd circle
			(at -2.45618 -8.439404)
			(size 0.3048 0.3048)
			(layers "F.Cu" "F.Mask" "F.Paste")
			(net "GND")
		)
		(pad "L30" smd circle
			(at -1.756156 -8.439404)
			(size 0.3048 0.3048)
			(layers "F.Cu" "F.Mask" "F.Paste")
			(net "GND")
		)
		(pad "L32" smd circle
			(at -0.4699 -8.058404)
			(size 0.3048 0.3048)
			(layers "F.Cu" "F.Mask" "F.Paste")
			(net "P1V8_NODE1")
		)
		(pad "L34" smd circle
			(at 0.230124 -8.058404)
			(size 0.3048 0.3048)
			(layers "F.Cu" "F.Mask" "F.Paste")
			(net "GND")
		)
		(pad "L37" smd circle
			(at 1.51638 -8.439404)
			(size 0.3048 0.3048)
			(layers "F.Cu" "F.Mask" "F.Paste")
			(net "GND")
		)
		(pad "L38" smd circle
			(at 2.216404 -8.439404)
			(size 0.3048 0.3048)
			(layers "F.Cu" "F.Mask" "F.Paste")
			(net "GND")
		)
		(pad "L41" smd circle
			(at 3.50266 -8.058404)
			(size 0.3048 0.3048)
			(layers "F.Cu" "F.Mask" "F.Paste")
			(net "P1V8_SUS_NODE1")
		)
		(pad "L42" smd circle
			(at 4.202684 -8.058404)
			(size 0.3048 0.3048)
			(layers "F.Cu" "F.Mask" "F.Paste")
			(net "P3V3_SUS_NODE1")
		)
		(pad "L44" smd circle
			(at 5.48894 -8.439404)
			(size 0.3048 0.3048)
			(layers "F.Cu" "F.Mask" "F.Paste")
			(net "GND")
		)
		(pad "L46" smd circle
			(at 6.188964 -8.439404)
			(size 0.3048 0.3048)
			(layers "F.Cu" "F.Mask" "F.Paste")
			(net "GND")
		)
		(pad "L48" smd circle
			(at 7.47522 -8.058404)
			(size 0.3048 0.3048)
			(layers "F.Cu" "F.Mask" "F.Paste")
			(net "GND")
		)
		(pad "L50" smd circle
			(at 8.175244 -8.058404)
			(size 0.3048 0.3048)
			(layers "F.Cu" "F.Mask" "F.Paste")
			(net "GND")
		)
		(pad "L52" smd circle
			(at 9.4615 -8.439404)
			(size 0.3048 0.3048)
			(layers "F.Cu" "F.Mask" "F.Paste")
			(net "NODE1_BIOS_MB_REV_ID1")
		)
		(pad "L54" smd circle
			(at 10.161524 -8.439404)
			(size 0.3048 0.3048)
			(layers "F.Cu" "F.Mask" "F.Paste")
			(net "H_CPU_NODE1_ERR2")
		)
		(pad "L57" smd circle
			(at 11.820398 -8.41502)
			(size 0.3048 0.3048)
			(layers "F.Cu" "F.Mask" "F.Paste")
			(net "GND")
		)
	)
)
